(kicad_pcb
	(version 20260206)
	(generator "pcbnew")
	(generator_version "10.0")
	(general
		(thickness 1.6)
		(legacy_teardrops no)
	)
	(paper "A4")
	(title_block
		(title "01162023_DA0F0TEBIF0_F0T_Expander_BD_F_brd_V02_OCP.brd")
		(comment 1 "Grand Teton / footprints 2046-2051 of 9728")
	)
	(layers
		(0 "F.Cu" signal "TOP")
		(4 "In1.Cu" signal "GND")
		(6 "In2.Cu" signal "VCC")
		(8 "In3.Cu" signal "VCC1")
		(10 "In4.Cu" signal "GND1")
		(12 "In5.Cu" signal "IN1")
		(14 "In6.Cu" signal "GND2")
		(16 "In7.Cu" signal "IN2")
		(18 "In8.Cu" signal "GND3")
		(20 "In9.Cu" signal "IN3")
		(22 "In10.Cu" signal "GND4")
		(24 "In11.Cu" signal "IN4")
		(26 "In12.Cu" signal "GND5")
		(28 "In13.Cu" signal "IN5")
		(30 "In14.Cu" signal "GND6")
		(32 "In15.Cu" signal "IN6")
		(34 "In16.Cu" signal "GND7")
		(2 "B.Cu" signal "BOTTOM")
		(9 "F.Adhes" user "F.Adhesive")
		(11 "B.Adhes" user "B.Adhesive")
		(13 "F.Paste" user "Package Geometry/Pastemask Top")
		(15 "B.Paste" user "Package Geometry/Pastemask Bottom")
		(5 "F.SilkS" user "Ref Des/Silkscreen Top")
		(7 "B.SilkS" user "Ref Des/Silkscreen Bottom")
		(1 "F.Mask" user "Board Geometry/Soldermask Top")
		(3 "B.Mask" user "Board Geometry/Soldermask Bottom")
		(17 "Dwgs.User" user "User.Drawings")
		(19 "Cmts.User" user "User.Comments")
		(21 "Eco1.User" user "User.Eco1")
		(23 "Eco2.User" user "User.Eco2")
		(25 "Edge.Cuts" user "Board Geometry/Outline")
		(27 "Margin" user)
		(31 "F.CrtYd" user "Package Geometry/Place Bound Top")
		(29 "B.CrtYd" user "Package Geometry/Place Bound Bottom")
		(35 "F.Fab" user "Ref Des/Assembly Top")
		(33 "B.Fab" user "Ref Des/Assembly Bottom")
	)
	(footprint ""
		(layer "F.Cu")
		(at 337.058 -245.237 -90)
		(property "Reference" "R1791"
			(at 0 0 270)
			(layer "F.SilkS")
			(hide yes)
			(effects
				(font
					(size 1.27 1.27)
				)
			)
		)
		(property "Value" ""
			(at 0 0 270)
			(layer "F.Fab")
			(effects
				(font
					(size 1.27 1.27)
				)
			)
		)
		(duplicate_pad_numbers_are_jumpers no)
		(fp_line
			(start -0.7874 0.4064)
			(end -0.7874 -0.4064)
			(stroke
				(width 0.1524)
				(type default)
			)
			(layer "F.SilkS")
		)
		(fp_line
			(start 0.7874 0.4064)
			(end -0.7874 0.4064)
			(stroke
				(width 0.1524)
				(type default)
			)
			(layer "F.SilkS")
		)
		(fp_line
			(start -0.7874 -0.4064)
			(end 0.7874 -0.4064)
			(stroke
				(width 0.1524)
				(type default)
			)
			(layer "F.SilkS")
		)
		(fp_line
			(start 0.7874 -0.4064)
			(end 0.7874 0.4064)
			(stroke
				(width 0.1524)
				(type default)
			)
			(layer "F.SilkS")
		)
		(fp_line
			(start -0.67945 0.3048)
			(end -0.67945 -0.305054)
			(stroke
				(width 0.1)
				(type default)
			)
			(layer "F.Fab")
		)
		(fp_line
			(start -0.12065 0.3048)
			(end -0.67945 0.3048)
			(stroke
				(width 0.1)
				(type default)
			)
			(layer "F.Fab")
		)
		(fp_line
			(start 0.120396 0.3048)
			(end 0.120396 0.2794)
			(stroke
				(width 0.1)
				(type default)
			)
			(layer "F.Fab")
		)
		(fp_line
			(start 0.67945 0.3048)
			(end 0.120396 0.3048)
			(stroke
				(width 0.1)
				(type default)
			)
			(layer "F.Fab")
		)
		(fp_line
			(start -0.12065 0.2794)
			(end -0.12065 0.3048)
			(stroke
				(width 0.1)
				(type default)
			)
			(layer "F.Fab")
		)
		(fp_line
			(start 0.120396 0.2794)
			(end -0.12065 0.2794)
			(stroke
				(width 0.1)
				(type default)
			)
			(layer "F.Fab")
		)
		(fp_line
			(start -0.12065 -0.2794)
			(end 0.12065 -0.2794)
			(stroke
				(width 0.1)
				(type default)
			)
			(layer "F.Fab")
		)
		(fp_line
			(start 0.12065 -0.2794)
			(end 0.12065 -0.3048)
			(stroke
				(width 0.1)
				(type default)
			)
			(layer "F.Fab")
		)
		(fp_line
			(start 0.12065 -0.3048)
			(end 0.67945 -0.3048)
			(stroke
				(width 0.1)
				(type default)
			)
			(layer "F.Fab")
		)
		(fp_line
			(start 0.67945 -0.3048)
			(end 0.67945 0.3048)
			(stroke
				(width 0.1)
				(type default)
			)
			(layer "F.Fab")
		)
		(fp_line
			(start -0.67945 -0.305054)
			(end -0.12065 -0.305054)
			(stroke
				(width 0.1)
				(type default)
			)
			(layer "F.Fab")
		)
		(fp_line
			(start -0.12065 -0.305054)
			(end -0.12065 -0.2794)
			(stroke
				(width 0.1)
				(type default)
			)
			(layer "F.Fab")
		)
		(pad "1" smd circle
			(at -0.40005 0 270)
			(size 0 0)
			(layers "F.Cu" "F.Mask" "F.Paste")
			(net "P3V3_AUX")
		)
		(pad "2" smd circle
			(at 0.40005 0 270)
			(size 0 0)
			(layers "F.Cu" "F.Mask" "F.Paste")
			(net "MB_SWB_PWR_EN")
		)
	)
	(footprint ""
		(layer "F.Cu")
		(at 150.311104 -61.386974)
		(property "Reference" "R4487"
			(at 0 0 0)
			(layer "F.SilkS")
			(hide yes)
			(effects
				(font
					(size 1.27 1.27)
				)
			)
		)
		(property "Value" ""
			(at 0 0 0)
			(layer "F.Fab")
			(effects
				(font
					(size 1.27 1.27)
				)
			)
		)
		(duplicate_pad_numbers_are_jumpers no)
		(fp_line
			(start -0.7874 -0.4064)
			(end 0.7874 -0.4064)
			(stroke
				(width 0.1524)
				(type default)
			)
			(layer "F.SilkS")
		)
		(fp_line
			(start -0.7874 0.4064)
			(end -0.7874 -0.4064)
			(stroke
				(width 0.1524)
				(type default)
			)
			(layer "F.SilkS")
		)
		(fp_line
			(start 0.7874 -0.4064)
			(end 0.7874 0.4064)
			(stroke
				(width 0.1524)
				(type default)
			)
			(layer "F.SilkS")
		)
		(fp_line
			(start 0.7874 0.4064)
			(end -0.7874 0.4064)
			(stroke
				(width 0.1524)
				(type default)
			)
			(layer "F.SilkS")
		)
		(fp_line
			(start -0.67945 -0.305054)
			(end -0.12065 -0.305054)
			(stroke
				(width 0.1)
				(type default)
			)
			(layer "F.Fab")
		)
		(fp_line
			(start -0.67945 0.3048)
			(end -0.67945 -0.305054)
			(stroke
				(width 0.1)
				(type default)
			)
			(layer "F.Fab")
		)
		(fp_line
			(start -0.12065 -0.305054)
			(end -0.12065 -0.2794)
			(stroke
				(width 0.1)
				(type default)
			)
			(layer "F.Fab")
		)
		(fp_line
			(start -0.12065 -0.2794)
			(end 0.12065 -0.2794)
			(stroke
				(width 0.1)
				(type default)
			)
			(layer "F.Fab")
		)
		(fp_line
			(start -0.12065 0.2794)
			(end -0.12065 0.3048)
			(stroke
				(width 0.1)
				(type default)
			)
			(layer "F.Fab")
		)
		(fp_line
			(start -0.12065 0.3048)
			(end -0.67945 0.3048)
			(stroke
				(width 0.1)
				(type default)
			)
			(layer "F.Fab")
		)
		(fp_line
			(start 0.120396 0.2794)
			(end -0.12065 0.2794)
			(stroke
				(width 0.1)
				(type default)
			)
			(layer "F.Fab")
		)
		(fp_line
			(start 0.120396 0.3048)
			(end 0.120396 0.2794)
			(stroke
				(width 0.1)
				(type default)
			)
			(layer "F.Fab")
		)
		(fp_line
			(start 0.12065 -0.3048)
			(end 0.67945 -0.3048)
			(stroke
				(width 0.1)
				(type default)
			)
			(layer "F.Fab")
		)
		(fp_line
			(start 0.12065 -0.2794)
			(end 0.12065 -0.3048)
			(stroke
				(width 0.1)
				(type default)
			)
			(layer "F.Fab")
		)
		(fp_line
			(start 0.67945 -0.3048)
			(end 0.67945 0.3048)
			(stroke
				(width 0.1)
				(type default)
			)
			(layer "F.Fab")
		)
		(fp_line
			(start 0.67945 0.3048)
			(end 0.120396 0.3048)
			(stroke
				(width 0.1)
				(type default)
			)
			(layer "F.Fab")
		)
		(pad "1" smd circle
			(at -0.40005 0)
			(size 0 0)
			(layers "F.Cu" "F.Mask" "F.Paste")
			(net "PWRGD_P3V3_SSD5")
		)
		(pad "2" smd circle
			(at 0.40005 0)
			(size 0 0)
			(layers "F.Cu" "F.Mask" "F.Paste")
			(net "PWRGD_P3V3_SSD5_R")
		)
	)
	(footprint ""
		(layer "F.Cu")
		(at 4.244086 -43.637708 -90)
		(property "Reference" "R5866"
			(at 0 0 270)
			(layer "F.SilkS")
			(hide yes)
			(effects
				(font
					(size 1.27 1.27)
				)
			)
		)
		(property "Value" ""
			(at 0 0 270)
			(layer "F.Fab")
			(effects
				(font
					(size 1.27 1.27)
				)
			)
		)
		(duplicate_pad_numbers_are_jumpers no)
		(fp_line
			(start -0.7874 0.4064)
			(end -0.7874 -0.4064)
			(stroke
				(width 0.1524)
				(type default)
			)
			(layer "F.SilkS")
		)
		(fp_line
			(start 0.7874 0.4064)
			(end -0.7874 0.4064)
			(stroke
				(width 0.1524)
				(type default)
			)
			(layer "F.SilkS")
		)
		(fp_line
			(start -0.7874 -0.4064)
			(end 0.7874 -0.4064)
			(stroke
				(width 0.1524)
				(type default)
			)
			(layer "F.SilkS")
		)
		(fp_line
			(start 0.7874 -0.4064)
			(end 0.7874 0.4064)
			(stroke
				(width 0.1524)
				(type default)
			)
			(layer "F.SilkS")
		)
		(fp_line
			(start -0.67945 0.3048)
			(end -0.67945 -0.305054)
			(stroke
				(width 0.1)
				(type default)
			)
			(layer "F.Fab")
		)
		(fp_line
			(start -0.12065 0.3048)
			(end -0.67945 0.3048)
			(stroke
				(width 0.1)
				(type default)
			)
			(layer "F.Fab")
		)
		(fp_line
			(start 0.120396 0.3048)
			(end 0.120396 0.2794)
			(stroke
				(width 0.1)
				(type default)
			)
			(layer "F.Fab")
		)
		(fp_line
			(start 0.67945 0.3048)
			(end 0.120396 0.3048)
			(stroke
				(width 0.1)
				(type default)
			)
			(layer "F.Fab")
		)
		(fp_line
			(start -0.12065 0.2794)
			(end -0.12065 0.3048)
			(stroke
				(width 0.1)
				(type default)
			)
			(layer "F.Fab")
		)
		(fp_line
			(start 0.120396 0.2794)
			(end -0.12065 0.2794)
			(stroke
				(width 0.1)
				(type default)
			)
			(layer "F.Fab")
		)
		(fp_line
			(start -0.12065 -0.2794)
			(end 0.12065 -0.2794)
			(stroke
				(width 0.1)
				(type default)
			)
			(layer "F.Fab")
		)
		(fp_line
			(start 0.12065 -0.2794)
			(end 0.12065 -0.3048)
			(stroke
				(width 0.1)
				(type default)
			)
			(layer "F.Fab")
		)
		(fp_line
			(start 0.12065 -0.3048)
			(end 0.67945 -0.3048)
			(stroke
				(width 0.1)
				(type default)
			)
			(layer "F.Fab")
		)
		(fp_line
			(start 0.67945 -0.3048)
			(end 0.67945 0.3048)
			(stroke
				(width 0.1)
				(type default)
			)
			(layer "F.Fab")
		)
		(fp_line
			(start -0.67945 -0.305054)
			(end -0.12065 -0.305054)
			(stroke
				(width 0.1)
				(type default)
			)
			(layer "F.Fab")
		)
		(fp_line
			(start -0.12065 -0.305054)
			(end -0.12065 -0.2794)
			(stroke
				(width 0.1)
				(type default)
			)
			(layer "F.Fab")
		)
		(pad "1" smd circle
			(at -0.40005 0 270)
			(size 0 0)
			(layers "F.Cu" "F.Mask" "F.Paste")
			(net "SSD0_AUX_P3V3_EN_R")
		)
		(pad "2" smd circle
			(at 0.40005 0 270)
			(size 0 0)
			(layers "F.Cu" "F.Mask" "F.Paste")
			(net "P3V3_SSD0_CO_EN")
		)
	)
	(footprint ""
		(layer "F.Cu")
		(at 101.89591 -113.547398 90)
		(property "Reference" "PR6863"
			(at 0 0 90)
			(layer "F.SilkS")
			(hide yes)
			(effects
				(font
					(size 1.27 1.27)
				)
			)
		)
		(property "Value" ""
			(at 0 0 90)
			(layer "F.Fab")
			(effects
				(font
					(size 1.27 1.27)
				)
			)
		)
		(duplicate_pad_numbers_are_jumpers no)
		(fp_line
			(start 0.7874 -0.4064)
			(end 0.7874 0.4064)
			(stroke
				(width 0.1524)
				(type default)
			)
			(layer "F.SilkS")
		)
		(fp_line
			(start -0.7874 -0.4064)
			(end 0.7874 -0.4064)
			(stroke
				(width 0.1524)
				(type default)
			)
			(layer "F.SilkS")
		)
		(fp_line
			(start 0.7874 0.4064)
			(end -0.7874 0.4064)
			(stroke
				(width 0.1524)
				(type default)
			)
			(layer "F.SilkS")
		)
		(fp_line
			(start -0.7874 0.4064)
			(end -0.7874 -0.4064)
			(stroke
				(width 0.1524)
				(type default)
			)
			(layer "F.SilkS")
		)
		(fp_line
			(start -0.12065 -0.305054)
			(end -0.12065 -0.2794)
			(stroke
				(width 0.1)
				(type default)
			)
			(layer "F.Fab")
		)
		(fp_line
			(start -0.67945 -0.305054)
			(end -0.12065 -0.305054)
			(stroke
				(width 0.1)
				(type default)
			)
			(layer "F.Fab")
		)
		(fp_line
			(start 0.67945 -0.3048)
			(end 0.67945 0.3048)
			(stroke
				(width 0.1)
				(type default)
			)
			(layer "F.Fab")
		)
		(fp_line
			(start 0.12065 -0.3048)
			(end 0.67945 -0.3048)
			(stroke
				(width 0.1)
				(type default)
			)
			(layer "F.Fab")
		)
		(fp_line
			(start 0.12065 -0.2794)
			(end 0.12065 -0.3048)
			(stroke
				(width 0.1)
				(type default)
			)
			(layer "F.Fab")
		)
		(fp_line
			(start -0.12065 -0.2794)
			(end 0.12065 -0.2794)
			(stroke
				(width 0.1)
				(type default)
			)
			(layer "F.Fab")
		)
		(fp_line
			(start 0.120396 0.2794)
			(end -0.12065 0.2794)
			(stroke
				(width 0.1)
				(type default)
			)
			(layer "F.Fab")
		)
		(fp_line
			(start -0.12065 0.2794)
			(end -0.12065 0.3048)
			(stroke
				(width 0.1)
				(type default)
			)
			(layer "F.Fab")
		)
		(fp_line
			(start 0.67945 0.3048)
			(end 0.120396 0.3048)
			(stroke
				(width 0.1)
				(type default)
			)
			(layer "F.Fab")
		)
		(fp_line
			(start 0.120396 0.3048)
			(end 0.120396 0.2794)
			(stroke
				(width 0.1)
				(type default)
			)
			(layer "F.Fab")
		)
		(fp_line
			(start -0.12065 0.3048)
			(end -0.67945 0.3048)
			(stroke
				(width 0.1)
				(type default)
			)
			(layer "F.Fab")
		)
		(fp_line
			(start -0.67945 0.3048)
			(end -0.67945 -0.305054)
			(stroke
				(width 0.1)
				(type default)
			)
			(layer "F.Fab")
		)
		(pad "1" smd circle
			(at -0.40005 0 90)
			(size 0 0)
			(layers "F.Cu" "F.Mask" "F.Paste")
			(net "P12V_NIC1_R")
		)
		(pad "2" smd circle
			(at 0.40005 0 90)
			(size 0 0)
			(layers "F.Cu" "F.Mask" "F.Paste")
			(net "P12V_NIC1_CO_AVIN_PD")
		)
	)
	(footprint ""
		(layer "F.Cu")
		(at 384.54584 -261.663434)
		(property "Reference" "C3561"
			(at 0 0 0)
			(layer "F.SilkS")
			(hide yes)
			(effects
				(font
					(size 1.27 1.27)
				)
			)
		)
		(property "Value" ""
			(at 0 0 0)
			(layer "F.Fab")
			(effects
				(font
					(size 1.27 1.27)
				)
			)
		)
		(duplicate_pad_numbers_are_jumpers no)
		(fp_line
			(start -1.2954 -0.5842)
			(end 1.2954 -0.5842)
			(stroke
				(width 0.1524)
				(type default)
			)
			(layer "F.SilkS")
		)
		(fp_line
			(start -1.2954 0.5842)
			(end -1.2954 -0.5842)
			(stroke
				(width 0.1524)
				(type default)
			)
			(layer "F.SilkS")
		)
		(fp_line
			(start 1.2954 -0.5842)
			(end 1.2954 0.5842)
			(stroke
				(width 0.1524)
				(type default)
			)
			(layer "F.SilkS")
		)
		(fp_line
			(start 1.2954 0.5842)
			(end -1.2954 0.5842)
			(stroke
				(width 0.1524)
				(type default)
			)
			(layer "F.SilkS")
		)
		(fp_line
			(start -1.1938 -0.4064)
			(end -0.8636 -0.4064)
			(stroke
				(width 0.1)
				(type default)
			)
			(layer "F.Fab")
		)
		(fp_line
			(start -1.1938 0.4064)
			(end -1.1938 -0.4064)
			(stroke
				(width 0.1)
				(type default)
			)
			(layer "F.Fab")
		)
		(fp_line
			(start -0.8636 -0.4572)
			(end 0.8636 -0.4572)
			(stroke
				(width 0.1)
				(type default)
			)
			(layer "F.Fab")
		)
		(fp_line
			(start -0.8636 -0.4064)
			(end -0.8636 -0.4572)
			(stroke
				(width 0.1)
				(type default)
			)
			(layer "F.Fab")
		)
		(fp_line
			(start -0.8636 0.4064)
			(end -1.1938 0.4064)
			(stroke
				(width 0.1)
				(type default)
			)
			(layer "F.Fab")
		)
		(fp_line
			(start -0.8636 0.4572)
			(end -0.8636 0.4064)
			(stroke
				(width 0.1)
				(type default)
			)
			(layer "F.Fab")
		)
		(fp_line
			(start 0.8636 -0.4572)
			(end 0.8636 -0.4064)
			(stroke
				(width 0.1)
				(type default)
			)
			(layer "F.Fab")
		)
		(fp_line
			(start 0.8636 -0.4064)
			(end 1.1938 -0.4064)
			(stroke
				(width 0.1)
				(type default)
			)
			(layer "F.Fab")
		)
		(fp_line
			(start 0.8636 0.4064)
			(end 0.8636 0.4572)
			(stroke
				(width 0.1)
				(type default)
			)
			(layer "F.Fab")
		)
		(fp_line
			(start 0.8636 0.4572)
			(end -0.8636 0.4572)
			(stroke
				(width 0.1)
				(type default)
			)
			(layer "F.Fab")
		)
		(fp_line
			(start 1.1938 -0.4064)
			(end 1.1938 0.4064)
			(stroke
				(width 0.1)
				(type default)
			)
			(layer "F.Fab")
		)
		(fp_line
			(start 1.1938 0.4064)
			(end 0.8636 0.4064)
			(stroke
				(width 0.1)
				(type default)
			)
			(layer "F.Fab")
		)
		(pad "1" smd rect
			(at -0.7366 0 270)
			(size 0.7112 0.8128)
			(layers "F.Cu" "F.Mask" "F.Paste")
			(net "PCEPLL3_VDDA18_PEX3")
		)
		(pad "2" smd rect
			(at 0.7366 0 270)
			(size 0.7112 0.8128)
			(layers "F.Cu" "F.Mask" "F.Paste")
			(net "GND")
		)
	)
	(footprint ""
		(layer "F.Cu")
		(at 361.188 -186.182 180)
		(property "Reference" "R4646"
			(at 0 0 180)
			(layer "F.SilkS")
			(hide yes)
			(effects
				(font
					(size 1.27 1.27)
				)
			)
		)
		(property "Value" ""
			(at 0 0 180)
			(layer "F.Fab")
			(effects
				(font
					(size 1.27 1.27)
				)
			)
		)
		(duplicate_pad_numbers_are_jumpers no)
		(fp_line
			(start 0.7874 0.4064)
			(end -0.7874 0.4064)
			(stroke
				(width 0.1524)
				(type default)
			)
			(layer "F.SilkS")
		)
		(fp_line
			(start 0.7874 -0.4064)
			(end 0.7874 0.4064)
			(stroke
				(width 0.1524)
				(type default)
			)
			(layer "F.SilkS")
		)
		(fp_line
			(start -0.7874 0.4064)
			(end -0.7874 -0.4064)
			(stroke
				(width 0.1524)
				(type default)
			)
			(layer "F.SilkS")
		)
		(fp_line
			(start -0.7874 -0.4064)
			(end 0.7874 -0.4064)
			(stroke
				(width 0.1524)
				(type default)
			)
			(layer "F.SilkS")
		)
		(fp_line
			(start 0.67945 0.3048)
			(end 0.120396 0.3048)
			(stroke
				(width 0.1)
				(type default)
			)
			(layer "F.Fab")
		)
		(fp_line
			(start 0.67945 -0.3048)
			(end 0.67945 0.3048)
			(stroke
				(width 0.1)
				(type default)
			)
			(layer "F.Fab")
		)
		(fp_line
			(start 0.12065 -0.2794)
			(end 0.12065 -0.3048)
			(stroke
				(width 0.1)
				(type default)
			)
			(layer "F.Fab")
		)
		(fp_line
			(start 0.12065 -0.3048)
			(end 0.67945 -0.3048)
			(stroke
				(width 0.1)
				(type default)
			)
			(layer "F.Fab")
		)
		(fp_line
			(start 0.120396 0.3048)
			(end 0.120396 0.2794)
			(stroke
				(width 0.1)
				(type default)
			)
			(layer "F.Fab")
		)
		(fp_line
			(start 0.120396 0.2794)
			(end -0.12065 0.2794)
			(stroke
				(width 0.1)
				(type default)
			)
			(layer "F.Fab")
		)
		(fp_line
			(start -0.12065 0.3048)
			(end -0.67945 0.3048)
			(stroke
				(width 0.1)
				(type default)
			)
			(layer "F.Fab")
		)
		(fp_line
			(start -0.12065 0.2794)
			(end -0.12065 0.3048)
			(stroke
				(width 0.1)
				(type default)
			)
			(layer "F.Fab")
		)
		(fp_line
			(start -0.12065 -0.2794)
			(end 0.12065 -0.2794)
			(stroke
				(width 0.1)
				(type default)
			)
			(layer "F.Fab")
		)
		(fp_line
			(start -0.12065 -0.305054)
			(end -0.12065 -0.2794)
			(stroke
				(width 0.1)
				(type default)
			)
			(layer "F.Fab")
		)
		(fp_line
			(start -0.67945 0.3048)
			(end -0.67945 -0.305054)
			(stroke
				(width 0.1)
				(type default)
			)
			(layer "F.Fab")
		)
		(fp_line
			(start -0.67945 -0.305054)
			(end -0.12065 -0.305054)
			(stroke
				(width 0.1)
				(type default)
			)
			(layer "F.Fab")
		)
		(pad "1" smd circle
			(at -0.40005 0 180)
			(size 0 0)
			(layers "F.Cu" "F.Mask" "F.Paste")
			(net "PRSNT_SSD3_FPGA_PCA9555_N")
		)
		(pad "2" smd circle
			(at 0.40005 0 180)
			(size 0 0)
			(layers "F.Cu" "F.Mask" "F.Paste")
			(net "PRSNT_SSD3_FPGA_R_N")
		)
	)
)
